# S9S_MB_2U (Grand Teton) — schematic netlist excerpt (pin names and nets, part order shuffled) for the footprints in the layout excerpt that follows; sources: Cadence DE-HDL packaged netlist, KiCad conversion of 03242023_DA0F0TMBIJ0_F0T_Motherboard_J_brd_V01_OCP.brd

R2208  Q_RES  0 5% CHIP  pkg 0402LF  page 236 : A = SMB_S3M_CPU0_3V3AUX_SDA_R ; B = SMB_S3M_CPU0_3V3AUX_SDA
R3534  Q_RES  33.2 1% CHIP  pkg 0402LF  page 194 : A = SMB_E1S_3V3AUX_ISO_SDA_R ; B = SMB_E1S_3V3AUX_ISO_SDA

(kicad_pcb
	(version 20260206)
	(generator "pcbnew")
	(generator_version "10.0")
	(general
		(thickness 1.6)
		(legacy_teardrops no)
	)
	(paper "A4")
	(title_block
		(title "03242023_DA0F0TMBIJ0_F0T_Motherboard_J_brd_V01_OCP.brd")
		(comment 1 "Grand Teton / footprints 1971-1972 of 6105")
	)
	(layers
		(0 "F.Cu" signal "TOP")
		(4 "In1.Cu" signal "GND")
		(6 "In2.Cu" signal "IN1")
		(8 "In3.Cu" signal "GND1")
		(10 "In4.Cu" signal "IN2")
		(12 "In5.Cu" signal "GND2")
		(14 "In6.Cu" signal "IN3")
		(16 "In7.Cu" signal "GND3")
		(18 "In8.Cu" signal "VCC")
		(20 "In9.Cu" signal "VCC1")
		(22 "In10.Cu" signal "GND4")
		(24 "In11.Cu" signal "IN4")
		(26 "In12.Cu" signal "GND5")
		(28 "In13.Cu" signal "IN5")
		(30 "In14.Cu" signal "GND6")
		(32 "In15.Cu" signal "IN6")
		(34 "In16.Cu" signal "GND7")
		(2 "B.Cu" signal "BOTTOM")
		(9 "F.Adhes" user "F.Adhesive")
		(11 "B.Adhes" user "B.Adhesive")
		(13 "F.Paste" user "Package Geometry/Pastemask Top")
		(15 "B.Paste" user "Package Geometry/Pastemask Bottom")
		(5 "F.SilkS" user "Ref Des/Silkscreen Top")
		(7 "B.SilkS" user "Ref Des/Silkscreen Bottom")
		(1 "F.Mask" user "Board Geometry/Soldermask Top")
		(3 "B.Mask" user "Board Geometry/Soldermask Bottom")
		(17 "Dwgs.User" user "User.Drawings")
		(19 "Cmts.User" user "User.Comments")
		(21 "Eco1.User" user "User.Eco1")
		(23 "Eco2.User" user "User.Eco2")
		(25 "Edge.Cuts" user "Board Geometry/Outline")
		(27 "Margin" user)
		(31 "F.CrtYd" user "Package Geometry/Place Bound Top")
		(29 "B.CrtYd" user "Package Geometry/Place Bound Bottom")
		(35 "F.Fab" user "Ref Des/Assembly Top")
		(33 "B.Fab" user "Ref Des/Assembly Bottom")
	)
	(footprint ""
		(layer "F.Cu")
		(at 223.70288 -44.922948)
		(property "Reference" "R3534"
			(at 0 0 0)
			(layer "F.SilkS")
			(hide yes)
			(effects
				(font
					(size 1.27 1.27)
				)
			)
		)
		(property "Value" ""
			(at 0 0 0)
			(layer "F.Fab")
			(effects
				(font
					(size 1.27 1.27)
				)
			)
		)
		(duplicate_pad_numbers_are_jumpers no)
		(fp_line
			(start -0.7874 -0.4064)
			(end 0.7874 -0.4064)
			(stroke
				(width 0.1524)
				(type default)
			)
			(layer "F.SilkS")
		)
		(fp_line
			(start -0.7874 0.4064)
			(end -0.7874 -0.4064)
			(stroke
				(width 0.1524)
				(type default)
			)
			(layer "F.SilkS")
		)
		(fp_line
			(start 0.7874 -0.4064)
			(end 0.7874 0.4064)
			(stroke
				(width 0.1524)
				(type default)
			)
			(layer "F.SilkS")
		)
		(fp_line
			(start 0.7874 0.4064)
			(end -0.7874 0.4064)
			(stroke
				(width 0.1524)
				(type default)
			)
			(layer "F.SilkS")
		)
		(fp_line
			(start -0.67945 -0.305054)
			(end -0.12065 -0.305054)
			(stroke
				(width 0.1)
				(type default)
			)
			(layer "F.Fab")
		)
		(fp_line
			(start -0.67945 0.3048)
			(end -0.67945 -0.305054)
			(stroke
				(width 0.1)
				(type default)
			)
			(layer "F.Fab")
		)
		(fp_line
			(start -0.12065 -0.305054)
			(end -0.12065 -0.2794)
			(stroke
				(width 0.1)
				(type default)
			)
			(layer "F.Fab")
		)
		(fp_line
			(start -0.12065 -0.2794)
			(end 0.12065 -0.2794)
			(stroke
				(width 0.1)
				(type default)
			)
			(layer "F.Fab")
		)
		(fp_line
			(start -0.12065 0.2794)
			(end -0.12065 0.3048)
			(stroke
				(width 0.1)
				(type default)
			)
			(layer "F.Fab")
		)
		(fp_line
			(start -0.12065 0.3048)
			(end -0.67945 0.3048)
			(stroke
				(width 0.1)
				(type default)
			)
			(layer "F.Fab")
		)
		(fp_line
			(start 0.120396 0.2794)
			(end -0.12065 0.2794)
			(stroke
				(width 0.1)
				(type default)
			)
			(layer "F.Fab")
		)
		(fp_line
			(start 0.120396 0.3048)
			(end 0.120396 0.2794)
			(stroke
				(width 0.1)
				(type default)
			)
			(layer "F.Fab")
		)
		(fp_line
			(start 0.12065 -0.3048)
			(end 0.67945 -0.3048)
			(stroke
				(width 0.1)
				(type default)
			)
			(layer "F.Fab")
		)
		(fp_line
			(start 0.12065 -0.2794)
			(end 0.12065 -0.3048)
			(stroke
				(width 0.1)
				(type default)
			)
			(layer "F.Fab")
		)
		(fp_line
			(start 0.67945 -0.3048)
			(end 0.67945 0.3048)
			(stroke
				(width 0.1)
				(type default)
			)
			(layer "F.Fab")
		)
		(fp_line
			(start 0.67945 0.3048)
			(end 0.120396 0.3048)
			(stroke
				(width 0.1)
				(type default)
			)
			(layer "F.Fab")
		)
		(pad "1" smd circle
			(at -0.40005 0)
			(size 0 0)
			(layers "F.Cu" "F.Mask" "F.Paste")
			(net "SMB_E1S_3V3AUX_ISO_SDA_R")
		)
		(pad "2" smd circle
			(at 0.40005 0)
			(size 0 0)
			(layers "F.Cu" "F.Mask" "F.Paste")
			(net "SMB_E1S_3V3AUX_ISO_SDA")
		)
	)
	(footprint ""
		(layer "F.Cu")
		(at 162.34283 -75.767438)
		(property "Reference" "R2208"
			(at 0 0 0)
			(layer "F.SilkS")
			(hide yes)
			(effects
				(font
					(size 1.27 1.27)
				)
			)
		)
		(property "Value" ""
			(at 0 0 0)
			(layer "F.Fab")
			(effects
				(font
					(size 1.27 1.27)
				)
			)
		)
		(duplicate_pad_numbers_are_jumpers no)
		(fp_line
			(start -0.7874 -0.4064)
			(end 0.7874 -0.4064)
			(stroke
				(width 0.1524)
				(type default)
			)
			(layer "F.SilkS")
		)
		(fp_line
			(start -0.7874 0.4064)
			(end -0.7874 -0.4064)
			(stroke
				(width 0.1524)
				(type default)
			)
			(layer "F.SilkS")
		)
		(fp_line
			(start 0.7874 -0.4064)
			(end 0.7874 0.4064)
			(stroke
				(width 0.1524)
				(type default)
			)
			(layer "F.SilkS")
		)
		(fp_line
			(start 0.7874 0.4064)
			(end -0.7874 0.4064)
			(stroke
				(width 0.1524)
				(type default)
			)
			(layer "F.SilkS")
		)
		(fp_line
			(start -0.67945 -0.305054)
			(end -0.12065 -0.305054)
			(stroke
				(width 0.1)
				(type default)
			)
			(layer "F.Fab")
		)
		(fp_line
			(start -0.67945 0.3048)
			(end -0.67945 -0.305054)
			(stroke
				(width 0.1)
				(type default)
			)
			(layer "F.Fab")
		)
		(fp_line
			(start -0.12065 -0.305054)
			(end -0.12065 -0.2794)
			(stroke
				(width 0.1)
				(type default)
			)
			(layer "F.Fab")
		)
		(fp_line
			(start -0.12065 -0.2794)
			(end 0.12065 -0.2794)
			(stroke
				(width 0.1)
				(type default)
			)
			(layer "F.Fab")
		)
		(fp_line
			(start -0.12065 0.2794)
			(end -0.12065 0.3048)
			(stroke
				(width 0.1)
				(type default)
			)
			(layer "F.Fab")
		)
		(fp_line
			(start -0.12065 0.3048)
			(end -0.67945 0.3048)
			(stroke
				(width 0.1)
				(type default)
			)
			(layer "F.Fab")
		)
		(fp_line
			(start 0.120396 0.2794)
			(end -0.12065 0.2794)
			(stroke
				(width 0.1)
				(type default)
			)
			(layer "F.Fab")
		)
		(fp_line
			(start 0.120396 0.3048)
			(end 0.120396 0.2794)
			(stroke
				(width 0.1)
				(type default)
			)
			(layer "F.Fab")
		)
		(fp_line
			(start 0.12065 -0.3048)
			(end 0.67945 -0.3048)
			(stroke
				(width 0.1)
				(type default)
			)
			(layer "F.Fab")
		)
		(fp_line
			(start 0.12065 -0.2794)
			(end 0.12065 -0.3048)
			(stroke
				(width 0.1)
				(type default)
			)
			(layer "F.Fab")
		)
		(fp_line
			(start 0.67945 -0.3048)
			(end 0.67945 0.3048)
			(stroke
				(width 0.1)
				(type default)
			)
			(layer "F.Fab")
		)
		(fp_line
			(start 0.67945 0.3048)
			(end 0.120396 0.3048)
			(stroke
				(width 0.1)
				(type default)
			)
			(layer "F.Fab")
		)
		(pad "1" smd circle
			(at -0.40005 0)
			(size 0 0)
			(layers "F.Cu" "F.Mask" "F.Paste")
			(net "SMB_S3M_CPU0_3V3AUX_SDA_R")
		)
		(pad "2" smd circle
			(at 0.40005 0)
			(size 0 0)
			(layers "F.Cu" "F.Mask" "F.Paste")
			(net "SMB_S3M_CPU0_3V3AUX_SDA")
		)
	)
)
